(kicad_pcb
	(version 20260206)
	(generator "pcbnew")
	(generator_version "10.0")
	(general
		(thickness 1.6)
		(legacy_teardrops no)
	)
	(paper "A4")
	(title_block
		(title "fcb — 12433-1M.1206WZS1330.brd")
		(comment 1 "Open Vault / Knox (Wiwynn) / footprints 146-150 of 495")
	)
	(layers
		(0 "F.Cu" signal "TOP")
		(4 "In1.Cu" signal "L2GND")
		(6 "In2.Cu" signal "L3VCC")
		(2 "B.Cu" signal "BOTTOM")
		(9 "F.Adhes" user "F.Adhesive")
		(11 "B.Adhes" user "B.Adhesive")
		(13 "F.Paste" user "Package Geometry/Pastemask Top")
		(15 "B.Paste" user "Package Geometry/Pastemask Bottom")
		(5 "F.SilkS" user "Ref Des/Silkscreen Top")
		(7 "B.SilkS" user "Ref Des/Silkscreen Bottom")
		(1 "F.Mask" user "Board Geometry/Soldermask Top")
		(3 "B.Mask" user "Board Geometry/Soldermask Bottom")
		(17 "Dwgs.User" user "User.Drawings")
		(19 "Cmts.User" user "User.Comments")
		(21 "Eco1.User" user "User.Eco1")
		(23 "Eco2.User" user "User.Eco2")
		(25 "Edge.Cuts" user "Board Geometry/Outline")
		(27 "Margin" user)
		(31 "F.CrtYd" user "Package Geometry/Place Bound Top")
		(29 "B.CrtYd" user "Package Geometry/Place Bound Bottom")
		(35 "F.Fab" user "Ref Des/Assembly Top")
		(33 "B.Fab" user "Ref Des/Assembly Bottom")
	)
	(footprint ""
		(layer "F.Cu")
		(at 19.3294 -277.0124 -90)
		(property "Reference" "TC16"
			(at 0 0 270)
			(layer "F.SilkS")
			(hide yes)
			(effects
				(font
					(size 1.27 1.27)
				)
			)
		)
		(property "Value" "ST15U25VDM-1-GP"
			(at 0 -9.6012 270)
			(unlocked yes)
			(layer "F.Fab")
			(hide yes)
			(effects
				(font
					(size 1.016 1.016)
					(thickness 0.1524)
				)
			)
		)
		(property "Device Type" "CT7343H79"
			(at 0 -11.1252 270)
			(unlocked yes)
			(layer "F.Fab")
			(hide yes)
			(effects
				(font
					(size 1.016 1.016)
					(thickness 0.1524)
				)
			)
		)
		(duplicate_pad_numbers_are_jumpers no)
		(fp_line
			(start -2.286 4.8768)
			(end -2.286 2.032)
			(stroke
				(width 0.1524)
				(type default)
			)
			(layer "F.SilkS")
		)
		(fp_line
			(start 2.286 4.8768)
			(end -2.286 4.8768)
			(stroke
				(width 0.1524)
				(type default)
			)
			(layer "F.SilkS")
		)
		(fp_line
			(start 2.286 2.032)
			(end 2.286 4.8768)
			(stroke
				(width 0.1524)
				(type default)
			)
			(layer "F.SilkS")
		)
		(fp_line
			(start 2.286 -2.032)
			(end 2.286 -4.8768)
			(stroke
				(width 0.1524)
				(type default)
			)
			(layer "F.SilkS")
		)
		(fp_line
			(start 2.1082 -4.699)
			(end -2.1082 -4.699)
			(stroke
				(width 0.508)
				(type default)
			)
			(layer "F.SilkS")
		)
		(fp_line
			(start -2.286 -4.8768)
			(end -2.286 -2.032)
			(stroke
				(width 0.1524)
				(type default)
			)
			(layer "F.SilkS")
		)
		(fp_line
			(start 2.286 -4.8768)
			(end -2.286 -4.8768)
			(stroke
				(width 0.1524)
				(type default)
			)
			(layer "F.SilkS")
		)
		(fp_rect
			(start -2.1463 3.6449)
			(end 2.1463 -3.6449)
			(stroke
				(width 0)
				(type default)
			)
			(fill no)
			(layer "F.CrtYd")
		)
		(fp_poly
			(pts
				(xy -2.54 4.953) (xy -2.54 4.2926) (xy -3.81 4.2926) (xy -3.81 -4.2926) (xy -2.54 -4.2926) (xy -2.54 -4.953)
				(xy 2.54 -4.953) (xy 2.54 -4.2926) (xy 3.81 -4.2926) (xy 3.81 -1.6256) (xy 2.1463 -1.6256) (xy 2.1463 -3.6449)
				(xy -2.1463 -3.6449) (xy -2.1463 3.6449) (xy 2.1463 3.6449) (xy 2.1463 -1.6129) (xy 3.81 -1.6129)
				(xy 3.81 4.2926) (xy 2.54 4.2926) (xy 2.54 4.953)
			)
			(stroke
				(width 0)
				(type default)
			)
			(fill no)
			(layer "F.CrtYd")
		)
		(fp_rect
			(start -2.54 4.953)
			(end 2.54 -4.953)
			(stroke
				(width 0)
				(type default)
			)
			(fill no)
			(layer "F.Fab")
		)
		(fp_rect
			(start -3.81 4.2926)
			(end -2.54 -4.2926)
			(stroke
				(width 0)
				(type default)
			)
			(fill no)
			(layer "F.Fab")
		)
		(fp_rect
			(start 2.54 4.2926)
			(end 3.81 -4.2926)
			(stroke
				(width 0)
				(type default)
			)
			(fill no)
			(layer "F.Fab")
		)
		(pad "1" smd rect
			(at 0 -3.1496 270)
			(size 2.413 2.286)
			(layers "F.Cu" "F.Mask" "F.Paste")
			(net "P12V")
		)
		(pad "2" smd rect
			(at 0 3.1496 270)
			(size 2.413 2.286)
			(layers "F.Cu" "F.Mask" "F.Paste")
			(net "GND")
		)
		(zone
			(layer "F.Cu")
			(hatch none 0.5)
			(connect_pads
				(clearance 0)
			)
			(min_thickness 0.25)
			(keepout
				(tracks allowed)
				(vias not_allowed)
				(pads allowed)
				(copperpour not_allowed)
				(footprints allowed)
			)
			(placement
				(enabled no)
				(sheetname "")
			)
			(fill
				(thermal_gap 0.5)
				(thermal_bridge_width 0.5)
				(island_removal_mode 0)
			)
			(polygon
				(pts
					(xy 14.732 -278.5237) (xy 14.732 -275.5011) (xy 17.6276 -275.5011) (xy 17.9578 -275.5011) (xy 17.9578 -278.5237)
					(xy 17.6276 -278.5237)
				)
			)
		)
		(zone
			(layer "F.Cu")
			(hatch none 0.5)
			(connect_pads
				(clearance 0)
			)
			(min_thickness 0.25)
			(keepout
				(tracks allowed)
				(vias not_allowed)
				(pads allowed)
				(copperpour not_allowed)
				(footprints allowed)
			)
			(placement
				(enabled no)
				(sheetname "")
			)
			(fill
				(thermal_gap 0.5)
				(thermal_bridge_width 0.5)
				(island_removal_mode 0)
			)
			(polygon
				(pts
					(xy 21.0185 -275.5011) (xy 23.9268 -275.5011) (xy 23.9268 -278.5237) (xy 21.0312 -278.5237) (xy 20.701 -278.5237)
					(xy 20.701 -275.5011)
				)
			)
		)
	)
	(footprint ""
		(layer "F.Cu")
		(at 5.947918 -434.623972 180)
		(property "Reference" "Q8"
			(at 0 0 180)
			(layer "F.SilkS")
			(hide yes)
			(effects
				(font
					(size 1.27 1.27)
				)
			)
		)
		(property "Value" "PMBS3904-1-GP"
			(at 0 -9.0932 180)
			(unlocked yes)
			(layer "F.Fab")
			(hide yes)
			(effects
				(font
					(size 1.016 1.016)
					(thickness 0.1524)
				)
			)
		)
		(property "Device Type" "SOT-23-10H44"
			(at 0 -10.6172 180)
			(unlocked yes)
			(layer "F.Fab")
			(hide yes)
			(effects
				(font
					(size 1.016 1.016)
					(thickness 0.1524)
				)
			)
		)
		(duplicate_pad_numbers_are_jumpers no)
		(fp_line
			(start 1.651 1.778)
			(end 1.651 -1.778)
			(stroke
				(width 0.1524)
				(type default)
			)
			(layer "F.SilkS")
		)
		(fp_line
			(start 1.651 -1.778)
			(end -1.651 -1.778)
			(stroke
				(width 0.1524)
				(type default)
			)
			(layer "F.SilkS")
		)
		(fp_line
			(start -0.635 1.8796)
			(end -1.7526 1.8796)
			(stroke
				(width 0.3302)
				(type default)
			)
			(layer "F.SilkS")
		)
		(fp_line
			(start -0.71628 2.15265)
			(end -1.26492 2.15265)
			(stroke
				(width 0.0127)
				(type default)
			)
			(layer "F.SilkS")
		)
		(fp_line
			(start -0.719074 2.145538)
			(end -1.265936 2.14122)
			(stroke
				(width 0.0127)
				(type default)
			)
			(layer "F.SilkS")
		)
		(fp_line
			(start -0.9906 1.86309)
			(end -0.701294 2.15265)
			(stroke
				(width 0.0127)
				(type default)
			)
			(layer "F.SilkS")
		)
		(fp_line
			(start -0.994156 1.8669)
			(end -0.987044 1.8669)
			(stroke
				(width 0.0127)
				(type default)
			)
			(layer "F.SilkS")
		)
		(fp_line
			(start -1.003808 1.876552)
			(end -0.977646 1.876552)
			(stroke
				(width 0.0127)
				(type default)
			)
			(layer "F.SilkS")
		)
		(fp_line
			(start -1.013206 1.88595)
			(end -0.967994 1.88595)
			(stroke
				(width 0.0127)
				(type default)
			)
			(layer "F.SilkS")
		)
		(fp_line
			(start -1.022858 1.895602)
			(end -0.958596 1.895602)
			(stroke
				(width 0.0127)
				(type default)
			)
			(layer "F.SilkS")
		)
		(fp_line
			(start -1.032256 1.905)
			(end -0.948944 1.905)
			(stroke
				(width 0.0127)
				(type default)
			)
			(layer "F.SilkS")
		)
		(fp_line
			(start -1.041908 1.914652)
			(end -0.939546 1.914652)
			(stroke
				(width 0.0127)
				(type default)
			)
			(layer "F.SilkS")
		)
		(fp_line
			(start -1.051306 1.92405)
			(end -0.929894 1.92405)
			(stroke
				(width 0.0127)
				(type default)
			)
			(layer "F.SilkS")
		)
		(fp_line
			(start -1.060958 1.933702)
			(end -0.920496 1.933702)
			(stroke
				(width 0.0127)
				(type default)
			)
			(layer "F.SilkS")
		)
		(fp_line
			(start -1.070356 1.9431)
			(end -0.910844 1.9431)
			(stroke
				(width 0.0127)
				(type default)
			)
			(layer "F.SilkS")
		)
		(fp_line
			(start -1.080008 1.952752)
			(end -0.901446 1.952752)
			(stroke
				(width 0.0127)
				(type default)
			)
			(layer "F.SilkS")
		)
		(fp_line
			(start -1.089406 1.96215)
			(end -0.891794 1.96215)
			(stroke
				(width 0.0127)
				(type default)
			)
			(layer "F.SilkS")
		)
		(fp_line
			(start -1.099058 1.971802)
			(end -0.882396 1.971802)
			(stroke
				(width 0.0127)
				(type default)
			)
			(layer "F.SilkS")
		)
		(fp_line
			(start -1.108456 1.9812)
			(end -0.872744 1.9812)
			(stroke
				(width 0.0127)
				(type default)
			)
			(layer "F.SilkS")
		)
		(fp_line
			(start -1.118108 1.990852)
			(end -0.863346 1.990852)
			(stroke
				(width 0.0127)
				(type default)
			)
			(layer "F.SilkS")
		)
		(fp_line
			(start -1.127506 2.00025)
			(end -0.853694 2.00025)
			(stroke
				(width 0.0127)
				(type default)
			)
			(layer "F.SilkS")
		)
		(fp_line
			(start -1.137158 2.009902)
			(end -0.844296 2.009902)
			(stroke
				(width 0.0127)
				(type default)
			)
			(layer "F.SilkS")
		)
		(fp_line
			(start -1.146556 2.0193)
			(end -0.834644 2.0193)
			(stroke
				(width 0.0127)
				(type default)
			)
			(layer "F.SilkS")
		)
		(fp_line
			(start -1.156208 2.028952)
			(end -0.825246 2.028952)
			(stroke
				(width 0.0127)
				(type default)
			)
			(layer "F.SilkS")
		)
		(fp_line
			(start -1.165606 2.03835)
			(end -0.815594 2.03835)
			(stroke
				(width 0.0127)
				(type default)
			)
			(layer "F.SilkS")
		)
		(fp_line
			(start -1.175258 2.048002)
			(end -0.806196 2.048002)
			(stroke
				(width 0.0127)
				(type default)
			)
			(layer "F.SilkS")
		)
		(fp_line
			(start -1.184656 2.0574)
			(end -0.796544 2.0574)
			(stroke
				(width 0.0127)
				(type default)
			)
			(layer "F.SilkS")
		)
		(fp_line
			(start -1.194308 2.067052)
			(end -0.787146 2.067052)
			(stroke
				(width 0.0127)
				(type default)
			)
			(layer "F.SilkS")
		)
		(fp_line
			(start -1.203706 2.07645)
			(end -0.777494 2.07645)
			(stroke
				(width 0.0127)
				(type default)
			)
			(layer "F.SilkS")
		)
		(fp_line
			(start -1.213358 2.086102)
			(end -0.768096 2.086102)
			(stroke
				(width 0.0127)
				(type default)
			)
			(layer "F.SilkS")
		)
		(fp_line
			(start -1.222756 2.0955)
			(end -0.758444 2.0955)
			(stroke
				(width 0.0127)
				(type default)
			)
			(layer "F.SilkS")
		)
		(fp_line
			(start -1.232408 2.105152)
			(end -0.749046 2.105152)
			(stroke
				(width 0.0127)
				(type default)
			)
			(layer "F.SilkS")
		)
		(fp_line
			(start -1.241806 2.11455)
			(end -0.739394 2.11455)
			(stroke
				(width 0.0127)
				(type default)
			)
			(layer "F.SilkS")
		)
		(fp_line
			(start -1.251458 2.124202)
			(end -0.729996 2.124202)
			(stroke
				(width 0.0127)
				(type default)
			)
			(layer "F.SilkS")
		)
		(fp_line
			(start -1.260856 2.1336)
			(end -0.720344 2.1336)
			(stroke
				(width 0.0127)
				(type default)
			)
			(layer "F.SilkS")
		)
		(fp_line
			(start -1.279144 2.15265)
			(end -0.701294 2.15265)
			(stroke
				(width 0.0127)
				(type default)
			)
			(layer "F.SilkS")
		)
		(fp_line
			(start -1.279398 2.152142)
			(end -0.9906 1.86309)
			(stroke
				(width 0.0127)
				(type default)
			)
			(layer "F.SilkS")
		)
		(fp_line
			(start -1.651 1.778)
			(end 1.651 1.778)
			(stroke
				(width 0.1524)
				(type default)
			)
			(layer "F.SilkS")
		)
		(fp_line
			(start -1.651 -1.778)
			(end -1.651 1.778)
			(stroke
				(width 0.1524)
				(type default)
			)
			(layer "F.SilkS")
		)
		(fp_line
			(start -1.7526 1.8796)
			(end -1.7526 0.9906)
			(stroke
				(width 0.3302)
				(type default)
			)
			(layer "F.SilkS")
		)
		(fp_poly
			(pts
				(xy -1.285748 2.159) (xy -1.285748 1.8796) (xy -1.778 1.8796) (xy -1.778 -1.8796) (xy 1.778 -1.8796)
				(xy 1.778 1.8796) (xy -0.694944 1.8796) (xy -0.694944 2.159)
			)
			(stroke
				(width 0)
				(type default)
			)
			(fill no)
			(layer "F.CrtYd")
		)
		(fp_poly
			(pts
				(xy -1.285748 2.159) (xy -1.285748 1.8796) (xy -1.778 1.8796) (xy -1.778 -1.8796) (xy 1.778 -1.8796)
				(xy 1.778 1.8796) (xy -0.694944 1.8796) (xy -0.694944 2.159)
			)
			(stroke
				(width 0)
				(type default)
			)
			(fill no)
			(layer "F.Fab")
		)
		(pad "1" smd rect
			(at -0.98425 0.9525 180)
			(size 0.762 1.143)
			(layers "F.Cu" "F.Mask" "F.Paste")
			(net "LED_DR_LED0_B")
		)
		(pad "2" smd rect
			(at 0.98425 0.9525 180)
			(size 0.762 1.143)
			(layers "F.Cu" "F.Mask" "F.Paste")
			(net "GND")
		)
		(pad "3" smd rect
			(at 0 -0.9525 180)
			(size 0.762 1.143)
			(layers "F.Cu" "F.Mask" "F.Paste")
			(net "LED_DR_LED0_BLUE")
		)
	)
	(footprint ""
		(layer "F.Cu")
		(at 35.541966 -153.45791 90)
		(property "Reference" "TP13"
			(at 0 0 90)
			(layer "F.SilkS")
			(hide yes)
			(effects
				(font
					(size 1.27 1.27)
				)
			)
		)
		(property "Value" "TPAD32-GP"
			(at 0 -3.166364 90)
			(unlocked yes)
			(layer "F.Fab")
			(hide yes)
			(effects
				(font
					(size 1.016 1.016)
					(thickness 0.1524)
				)
			)
		)
		(property "Device Type" "TPAD32"
			(at 0 -4.690618 90)
			(unlocked yes)
			(layer "F.Fab")
			(hide yes)
			(effects
				(font
					(size 1.016 1.016)
					(thickness 0.1524)
				)
			)
		)
		(duplicate_pad_numbers_are_jumpers no)
		(fp_poly
			(pts
				(arc
					(start 0.7112 0)
					(mid -0.7112 0)
					(end 0.7112 0)
				)
			)
			(stroke
				(width 0)
				(type default)
			)
			(fill no)
			(layer "F.CrtYd")
		)
		(fp_poly
			(pts
				(arc
					(start 0.7112 0)
					(mid -0.7112 0)
					(end 0.7112 0)
				)
			)
			(stroke
				(width 0)
				(type default)
			)
			(fill no)
			(layer "F.Fab")
		)
		(pad "1" smd circle
			(at 0 0 90)
			(size 0.8128 0.8128)
			(layers "F.Cu" "F.Mask" "F.Paste")
			(net "NCT7904_VSEN13")
		)
	)
	(footprint ""
		(layer "F.Cu")
		(at 23.622 -367.411 -90)
		(property "Reference" "PR3"
			(at 0 0 270)
			(layer "F.SilkS")
			(hide yes)
			(effects
				(font
					(size 1.27 1.27)
				)
			)
		)
		(property "Value" "51K1R2F-GP"
			(at 0.064008 -3.993896 270)
			(unlocked yes)
			(layer "F.Fab")
			(hide yes)
			(effects
				(font
					(size 1.016 1.016)
					(thickness 0.1524)
				)
			)
		)
		(property "Device Type" "R402H16"
			(at 0.064008 -5.517896 270)
			(unlocked yes)
			(layer "F.Fab")
			(hide yes)
			(effects
				(font
					(size 1.016 1.016)
					(thickness 0.1524)
				)
			)
		)
		(duplicate_pad_numbers_are_jumpers no)
		(fp_line
			(start -0.508 -0.9398)
			(end -0.508 0.9398)
			(stroke
				(width 0.1524)
				(type default)
			)
			(layer "F.SilkS")
		)
		(fp_line
			(start 0.508 -0.9398)
			(end -0.508 -0.9398)
			(stroke
				(width 0.1524)
				(type default)
			)
			(layer "F.SilkS")
		)
		(fp_rect
			(start -0.508 0.9398)
			(end 0.508 -0.9398)
			(stroke
				(width 0)
				(type default)
			)
			(fill no)
			(layer "F.CrtYd")
		)
		(fp_rect
			(start -0.508 0.9398)
			(end 0.508 -0.9398)
			(stroke
				(width 0)
				(type default)
			)
			(fill no)
			(layer "F.Fab")
		)
		(pad "1" smd custom
			(at 0 -0.4445 270)
			(size 0.1397 0.1397)
			(layers "F.Cu" "F.Mask" "F.Paste")
			(net "ADM1276_ISET")
			(options
				(clearance outline)
				(anchor circle)
			)
			(primitives
				(gr_poly
					(pts
						(arc
							(start -0.1778 -0.2794)
							(mid -0.249642 -0.249642)
							(end -0.2794 -0.1778)
						)
						(arc
							(start -0.2794 0.1778)
							(mid -0.249642 0.249642)
							(end -0.1778 0.2794)
						)
						(arc
							(start 0.1778 0.2794)
							(mid 0.249642 0.249642)
							(end 0.2794 0.1778)
						)
						(arc
							(start 0.2794 -0.1778)
							(mid 0.249642 -0.249642)
							(end 0.1778 -0.2794)
						)
					)
					(width 0)
					(fill yes)
				)
			)
		)
		(pad "2" smd custom
			(at 0 0.4445 270)
			(size 0.1397 0.1397)
			(layers "F.Cu" "F.Mask" "F.Paste")
			(net "GND")
			(options
				(clearance outline)
				(anchor circle)
			)
			(primitives
				(gr_poly
					(pts
						(arc
							(start -0.1778 -0.2794)
							(mid -0.249642 -0.249642)
							(end -0.2794 -0.1778)
						)
						(arc
							(start -0.2794 0.1778)
							(mid -0.249642 0.249642)
							(end -0.1778 0.2794)
						)
						(arc
							(start 0.1778 0.2794)
							(mid 0.249642 0.249642)
							(end 0.2794 0.1778)
						)
						(arc
							(start 0.2794 -0.1778)
							(mid 0.249642 -0.249642)
							(end 0.1778 -0.2794)
						)
					)
					(width 0)
					(fill yes)
				)
			)
		)
	)
	(footprint ""
		(layer "F.Cu")
		(at 9.9568 -87.757)
		(property "Reference" "R30"
			(at 0 0 0)
			(layer "F.SilkS")
			(hide yes)
			(effects
				(font
					(size 1.27 1.27)
				)
			)
		)
		(property "Value" "0R2J-2-GP"
			(at 0.064008 -3.993896 0)
			(unlocked yes)
			(layer "F.Fab")
			(hide yes)
			(effects
				(font
					(size 1.016 1.016)
					(thickness 0.1524)
				)
			)
		)
		(property "Device Type" "R402H16"
			(at 0.064008 -5.517896 0)
			(unlocked yes)
			(layer "F.Fab")
			(hide yes)
			(effects
				(font
					(size 1.016 1.016)
					(thickness 0.1524)
				)
			)
		)
		(duplicate_pad_numbers_are_jumpers no)
		(fp_line
			(start -0.508 -0.9398)
			(end -0.508 0.9398)
			(stroke
				(width 0.1524)
				(type default)
			)
			(layer "F.SilkS")
		)
		(fp_line
			(start 0.508 -0.9398)
			(end -0.508 -0.9398)
			(stroke
				(width 0.1524)
				(type default)
			)
			(layer "F.SilkS")
		)
		(fp_rect
			(start -0.508 0.9398)
			(end 0.508 -0.9398)
			(stroke
				(width 0)
				(type default)
			)
			(fill no)
			(layer "F.CrtYd")
		)
		(fp_rect
			(start -0.508 0.9398)
			(end 0.508 -0.9398)
			(stroke
				(width 0)
				(type default)
			)
			(fill no)
			(layer "F.Fab")
		)
		(pad "1" smd custom
			(at 0 -0.4445)
			(size 0.1397 0.1397)
			(layers "F.Cu" "F.Mask" "F.Paste")
			(net "LED_DR_LED4_K")
			(options
				(clearance outline)
				(anchor circle)
			)
			(primitives
				(gr_poly
					(pts
						(arc
							(start -0.1778 -0.2794)
							(mid -0.249642 -0.249642)
							(end -0.2794 -0.1778)
						)
						(arc
							(start -0.2794 0.1778)
							(mid -0.249642 0.249642)
							(end -0.1778 0.2794)
						)
						(arc
							(start 0.1778 0.2794)
							(mid 0.249642 0.249642)
							(end 0.2794 0.1778)
						)
						(arc
							(start 0.2794 -0.1778)
							(mid 0.249642 -0.249642)
							(end 0.1778 -0.2794)
						)
					)
					(width 0)
					(fill yes)
				)
			)
		)
		(pad "2" smd custom
			(at 0 0.4445)
			(size 0.1397 0.1397)
			(layers "F.Cu" "F.Mask" "F.Paste")
			(net "GND")
			(options
				(clearance outline)
				(anchor circle)
			)
			(primitives
				(gr_poly
					(pts
						(arc
							(start -0.1778 -0.2794)
							(mid -0.249642 -0.249642)
							(end -0.2794 -0.1778)
						)
						(arc
							(start -0.2794 0.1778)
							(mid -0.249642 0.249642)
							(end -0.1778 0.2794)
						)
						(arc
							(start 0.1778 0.2794)
							(mid 0.249642 0.249642)
							(end 0.2794 0.1778)
						)
						(arc
							(start 0.2794 -0.1778)
							(mid 0.249642 -0.249642)
							(end 0.1778 -0.2794)
						)
					)
					(width 0)
					(fill yes)
				)
			)
		)
	)
)
